# T6G (Grand Teton) — schematic netlist excerpt (pin names and nets, part order shuffled) for the footprints in the layout excerpt that follows; sources: Cadence DE-HDL packaged netlist, KiCad conversion of 04192023_DAF0TMB3IC0_F0TG_MB_C_brd_V02_OCP.brd

C1571  Q_CAP_DIFFBUS  DIFF BUS_0.22UF 6.3V 20% X6S  pkg C0201  page 65 : \1\ = P5E_CPU0_G3_TX_C_DP<4> ; \2\ = P5E_CPU0_G3_TX_DP<4>
C753  Q_CAP_DIFFBUS  DIFF BUS_0.22UF 6.3V 20% X6S  pkg C0201  page 66 : \1\ = P5E_CPU1_P2_TX_C_DP<10> ; \2\ = P5E_CPU1_P2_TX_DP<10>
PR3988  Q_RES  0 5% CHIP  pkg 0402LF  page 264 : A = HSC_SCREF ; B = HSC_SCREF_3

(kicad_pcb
	(version 20260206)
	(generator "pcbnew")
	(generator_version "10.0")
	(general
		(thickness 1.6)
		(legacy_teardrops no)
	)
	(paper "A4")
	(title_block
		(title "04192023_DAF0TMB3IC0_F0TG_MB_C_brd_V02_OCP.brd")
		(comment 1 "Grand Teton / footprints 1430-1432 of 8354")
	)
	(layers
		(0 "F.Cu" signal "TOP")
		(4 "In1.Cu" signal "GND")
		(6 "In2.Cu" signal "IN1")
		(8 "In3.Cu" signal "GND1")
		(10 "In4.Cu" signal "IN2")
		(12 "In5.Cu" signal "GND2")
		(14 "In6.Cu" signal "IN3")
		(16 "In7.Cu" signal "GND3")
		(18 "In8.Cu" signal "VCC")
		(20 "In9.Cu" signal "VCC1")
		(22 "In10.Cu" signal "GND4")
		(24 "In11.Cu" signal "IN4")
		(26 "In12.Cu" signal "GND5")
		(28 "In13.Cu" signal "IN5")
		(30 "In14.Cu" signal "GND6")
		(32 "In15.Cu" signal "IN6")
		(34 "In16.Cu" signal "GND7")
		(2 "B.Cu" signal "BOTTOM")
		(9 "F.Adhes" user "F.Adhesive")
		(11 "B.Adhes" user "B.Adhesive")
		(13 "F.Paste" user "Package Geometry/Pastemask Top")
		(15 "B.Paste" user "Package Geometry/Pastemask Bottom")
		(5 "F.SilkS" user "Ref Des/Silkscreen Top")
		(7 "B.SilkS" user "Ref Des/Silkscreen Bottom")
		(1 "F.Mask" user "Board Geometry/Soldermask Top")
		(3 "B.Mask" user "Board Geometry/Soldermask Bottom")
		(17 "Dwgs.User" user "User.Drawings")
		(19 "Cmts.User" user "User.Comments")
		(21 "Eco1.User" user "User.Eco1")
		(23 "Eco2.User" user "User.Eco2")
		(25 "Edge.Cuts" user "Board Geometry/Outline")
		(27 "Margin" user)
		(31 "F.CrtYd" user "Package Geometry/Place Bound Top")
		(29 "B.CrtYd" user "Package Geometry/Place Bound Bottom")
		(35 "F.Fab" user "Ref Des/Assembly Top")
		(33 "B.Fab" user "Ref Des/Assembly Bottom")
	)
	(footprint ""
		(layer "F.Cu")
		(at 215.4301 -408.084782)
		(property "Reference" "PR3988"
			(at 0 0 0)
			(layer "F.SilkS")
			(hide yes)
			(effects
				(font
					(size 1.27 1.27)
				)
			)
		)
		(property "Value" ""
			(at 0 0 0)
			(layer "F.Fab")
			(effects
				(font
					(size 1.27 1.27)
				)
			)
		)
		(duplicate_pad_numbers_are_jumpers no)
		(fp_line
			(start -0.7874 -0.4064)
			(end 0.7874 -0.4064)
			(stroke
				(width 0.1524)
				(type default)
			)
			(layer "F.SilkS")
		)
		(fp_line
			(start -0.7874 0.4064)
			(end -0.7874 -0.4064)
			(stroke
				(width 0.1524)
				(type default)
			)
			(layer "F.SilkS")
		)
		(fp_line
			(start 0.7874 -0.4064)
			(end 0.7874 0.4064)
			(stroke
				(width 0.1524)
				(type default)
			)
			(layer "F.SilkS")
		)
		(fp_line
			(start 0.7874 0.4064)
			(end -0.7874 0.4064)
			(stroke
				(width 0.1524)
				(type default)
			)
			(layer "F.SilkS")
		)
		(fp_line
			(start -0.67945 -0.305054)
			(end -0.12065 -0.305054)
			(stroke
				(width 0.1)
				(type default)
			)
			(layer "F.Fab")
		)
		(fp_line
			(start -0.67945 0.3048)
			(end -0.67945 -0.305054)
			(stroke
				(width 0.1)
				(type default)
			)
			(layer "F.Fab")
		)
		(fp_line
			(start -0.12065 -0.305054)
			(end -0.12065 -0.2794)
			(stroke
				(width 0.1)
				(type default)
			)
			(layer "F.Fab")
		)
		(fp_line
			(start -0.12065 -0.2794)
			(end 0.12065 -0.2794)
			(stroke
				(width 0.1)
				(type default)
			)
			(layer "F.Fab")
		)
		(fp_line
			(start -0.12065 0.2794)
			(end -0.12065 0.3048)
			(stroke
				(width 0.1)
				(type default)
			)
			(layer "F.Fab")
		)
		(fp_line
			(start -0.12065 0.3048)
			(end -0.67945 0.3048)
			(stroke
				(width 0.1)
				(type default)
			)
			(layer "F.Fab")
		)
		(fp_line
			(start 0.120396 0.2794)
			(end -0.12065 0.2794)
			(stroke
				(width 0.1)
				(type default)
			)
			(layer "F.Fab")
		)
		(fp_line
			(start 0.120396 0.3048)
			(end 0.120396 0.2794)
			(stroke
				(width 0.1)
				(type default)
			)
			(layer "F.Fab")
		)
		(fp_line
			(start 0.12065 -0.3048)
			(end 0.67945 -0.3048)
			(stroke
				(width 0.1)
				(type default)
			)
			(layer "F.Fab")
		)
		(fp_line
			(start 0.12065 -0.2794)
			(end 0.12065 -0.3048)
			(stroke
				(width 0.1)
				(type default)
			)
			(layer "F.Fab")
		)
		(fp_line
			(start 0.67945 -0.3048)
			(end 0.67945 0.3048)
			(stroke
				(width 0.1)
				(type default)
			)
			(layer "F.Fab")
		)
		(fp_line
			(start 0.67945 0.3048)
			(end 0.120396 0.3048)
			(stroke
				(width 0.1)
				(type default)
			)
			(layer "F.Fab")
		)
		(pad "1" smd circle
			(at -0.40005 0)
			(size 0 0)
			(layers "F.Cu" "F.Mask" "F.Paste")
			(net "HSC_SCREF")
		)
		(pad "2" smd circle
			(at 0.40005 0)
			(size 0 0)
			(layers "F.Cu" "F.Mask" "F.Paste")
			(net "HSC_SCREF_3")
		)
	)
	(footprint ""
		(layer "F.Cu")
		(at 161.337244 -375.49963 -90)
		(property "Reference" "C753"
			(at 0 0 270)
			(layer "F.SilkS")
			(hide yes)
			(effects
				(font
					(size 1.27 1.27)
				)
			)
		)
		(property "Value" ""
			(at 0 0 270)
			(layer "F.Fab")
			(effects
				(font
					(size 1.27 1.27)
				)
			)
		)
		(duplicate_pad_numbers_are_jumpers no)
		(fp_line
			(start -0.299974 0.150114)
			(end -0.299974 -0.150114)
			(stroke
				(width 0.1)
				(type default)
			)
			(layer "F.Fab")
		)
		(fp_line
			(start 0.299974 0.150114)
			(end -0.299974 0.150114)
			(stroke
				(width 0.1)
				(type default)
			)
			(layer "F.Fab")
		)
		(fp_line
			(start -0.299974 -0.150114)
			(end 0.299974 -0.150114)
			(stroke
				(width 0.1)
				(type default)
			)
			(layer "F.Fab")
		)
		(fp_line
			(start 0.299974 -0.150114)
			(end 0.299974 0.150114)
			(stroke
				(width 0.1)
				(type default)
			)
			(layer "F.Fab")
		)
		(pad "1" smd rect
			(at -0.2667 0 270)
			(size 0.3048 0.381)
			(layers "F.Cu" "F.Mask" "F.Paste")
			(net "P5E_CPU1_P2_TX_C_DP<10>")
		)
		(pad "2" smd rect
			(at 0.2667 0 270)
			(size 0.3048 0.381)
			(layers "F.Cu" "F.Mask" "F.Paste")
			(net "P5E_CPU1_P2_TX_DP<10>")
		)
	)
	(footprint ""
		(layer "F.Cu")
		(at 421.961564 -17.624298 90)
		(property "Reference" "C1571"
			(at 0 0 90)
			(layer "F.SilkS")
			(hide yes)
			(effects
				(font
					(size 1.27 1.27)
				)
			)
		)
		(property "Value" ""
			(at 0 0 90)
			(layer "F.Fab")
			(effects
				(font
					(size 1.27 1.27)
				)
			)
		)
		(duplicate_pad_numbers_are_jumpers no)
		(fp_line
			(start 0.299974 -0.150114)
			(end 0.299974 0.150114)
			(stroke
				(width 0.1)
				(type default)
			)
			(layer "F.Fab")
		)
		(fp_line
			(start -0.299974 -0.150114)
			(end 0.299974 -0.150114)
			(stroke
				(width 0.1)
				(type default)
			)
			(layer "F.Fab")
		)
		(fp_line
			(start 0.299974 0.150114)
			(end -0.299974 0.150114)
			(stroke
				(width 0.1)
				(type default)
			)
			(layer "F.Fab")
		)
		(fp_line
			(start -0.299974 0.150114)
			(end -0.299974 -0.150114)
			(stroke
				(width 0.1)
				(type default)
			)
			(layer "F.Fab")
		)
		(pad "1" smd rect
			(at -0.2667 0 90)
			(size 0.3048 0.381)
			(layers "F.Cu" "F.Mask" "F.Paste")
			(net "P5E_CPU0_G3_TX_C_DP<4>")
		)
		(pad "2" smd rect
			(at 0.2667 0 90)
			(size 0.3048 0.381)
			(layers "F.Cu" "F.Mask" "F.Paste")
			(net "P5E_CPU0_G3_TX_DP<4>")
		)
	)
)
